(kicad_pcb
	(version 20260206)
	(generator "pcbnew")
	(generator_version "10.0")
	(general
		(thickness 1.6)
		(legacy_teardrops no)
	)
	(paper "A4")
	(title_block
		(title "01162023_DA0F0TEBIF0_F0T_Expander_BD_F_brd_V02_OCP.brd")
		(comment 1 "Grand Teton / footprints 5531-5532 of 9728")
	)
	(layers
		(0 "F.Cu" signal "TOP")
		(4 "In1.Cu" signal "GND")
		(6 "In2.Cu" signal "VCC")
		(8 "In3.Cu" signal "VCC1")
		(10 "In4.Cu" signal "GND1")
		(12 "In5.Cu" signal "IN1")
		(14 "In6.Cu" signal "GND2")
		(16 "In7.Cu" signal "IN2")
		(18 "In8.Cu" signal "GND3")
		(20 "In9.Cu" signal "IN3")
		(22 "In10.Cu" signal "GND4")
		(24 "In11.Cu" signal "IN4")
		(26 "In12.Cu" signal "GND5")
		(28 "In13.Cu" signal "IN5")
		(30 "In14.Cu" signal "GND6")
		(32 "In15.Cu" signal "IN6")
		(34 "In16.Cu" signal "GND7")
		(2 "B.Cu" signal "BOTTOM")
		(9 "F.Adhes" user "F.Adhesive")
		(11 "B.Adhes" user "B.Adhesive")
		(13 "F.Paste" user "Package Geometry/Pastemask Top")
		(15 "B.Paste" user "Package Geometry/Pastemask Bottom")
		(5 "F.SilkS" user "Ref Des/Silkscreen Top")
		(7 "B.SilkS" user "Ref Des/Silkscreen Bottom")
		(1 "F.Mask" user "Board Geometry/Soldermask Top")
		(3 "B.Mask" user "Board Geometry/Soldermask Bottom")
		(17 "Dwgs.User" user "User.Drawings")
		(19 "Cmts.User" user "User.Comments")
		(21 "Eco1.User" user "User.Eco1")
		(23 "Eco2.User" user "User.Eco2")
		(25 "Edge.Cuts" user "Board Geometry/Outline")
		(27 "Margin" user)
		(31 "F.CrtYd" user "Package Geometry/Place Bound Top")
		(29 "B.CrtYd" user "Package Geometry/Place Bound Bottom")
		(35 "F.Fab" user "Ref Des/Assembly Top")
		(33 "B.Fab" user "Ref Des/Assembly Bottom")
	)
	(footprint ""
		(layer "F.Cu")
		(at 245.164864 -26.785062 180)
		(property "Reference" "J38"
			(at 4.352036 -11.16457 90)
			(unlocked yes)
			(layer "F.SilkS")
			(effects
				(font
					(size 0.7874 0.5842)
					(thickness 0.1524)
				)
			)
		)
		(property "Value" ""
			(at 0 0 180)
			(layer "F.Fab")
			(effects
				(font
					(size 1.27 1.27)
				)
			)
		)
		(duplicate_pad_numbers_are_jumpers no)
		(fp_line
			(start 3.150108 12.115038)
			(end 1.529334 12.115038)
			(stroke
				(width 0.1524)
				(type default)
			)
			(layer "F.SilkS")
		)
		(fp_line
			(start 3.074924 12.014962)
			(end 1.632204 12.014962)
			(stroke
				(width 0.1524)
				(type default)
			)
			(layer "F.SilkS")
		)
		(fp_line
			(start 1.632204 -12.014962)
			(end 3.074924 -12.014962)
			(stroke
				(width 0.1524)
				(type default)
			)
			(layer "F.SilkS")
		)
		(fp_line
			(start 1.529334 -12.115038)
			(end 3.150108 -12.115038)
			(stroke
				(width 0.1524)
				(type default)
			)
			(layer "F.SilkS")
		)
		(fp_line
			(start -1.529334 12.115038)
			(end -3.150108 12.115038)
			(stroke
				(width 0.1524)
				(type default)
			)
			(layer "F.SilkS")
		)
		(fp_line
			(start -1.632204 12.014962)
			(end -3.074924 12.014962)
			(stroke
				(width 0.1524)
				(type default)
			)
			(layer "F.SilkS")
		)
		(fp_line
			(start -3.074924 -12.014962)
			(end -1.632204 -12.014962)
			(stroke
				(width 0.1524)
				(type default)
			)
			(layer "F.SilkS")
		)
		(fp_line
			(start -3.150108 -12.115038)
			(end -1.529334 -12.115038)
			(stroke
				(width 0.1524)
				(type default)
			)
			(layer "F.SilkS")
		)
		(fp_poly
			(pts
				(xy 3.264408 -8.838946) (xy 3.68681 -10.10666) (xy 4.531868 -9.261602)
			)
			(stroke
				(width 0)
				(type default)
			)
			(fill yes)
			(layer "F.SilkS")
		)
		(fp_line
			(start 3.074924 12.014962)
			(end -3.074924 12.014962)
			(stroke
				(width 0.1)
				(type default)
			)
			(layer "F.Fab")
		)
		(fp_line
			(start 3.074924 -12.014962)
			(end 3.074924 12.014962)
			(stroke
				(width 0.1)
				(type default)
			)
			(layer "F.Fab")
		)
		(fp_line
			(start -3.074924 12.014962)
			(end -3.074924 -12.014962)
			(stroke
				(width 0.1)
				(type default)
			)
			(layer "F.Fab")
		)
		(fp_line
			(start -3.074924 -12.014962)
			(end 3.074924 -12.014962)
			(stroke
				(width 0.1)
				(type default)
			)
			(layer "F.Fab")
		)
		(fp_poly
			(pts
				(xy 3.348736 -7.994904) (xy 4.543806 -8.592566) (xy 4.543806 -7.397496)
			)
			(stroke
				(width 0)
				(type default)
			)
			(fill yes)
			(layer "F.Fab")
		)
		(pad "" np_thru_hole circle
			(at -1.75006 -9.815068 90)
			(size 1.1176 1.1176)
			(drill 1.1176)
			(layers "*.Cu" "*.Mask")
			(clearance 0.381)
			(thermal_gap 0.381)
		)
		(pad "" np_thru_hole circle
			(at 0 9.815068 90)
			(size 1.1176 1.1176)
			(drill 1.1176)
			(layers "*.Cu" "*.Mask")
			(clearance 0.381)
			(thermal_gap 0.381)
		)
		(pad "A1" smd rect
			(at 2.29997 -7.994904 90)
			(size 0.381 1.27)
			(layers "F.Cu" "F.Mask" "F.Paste")
			(net "GND")
		)
		(pad "A2" smd rect
			(at 2.29997 -7.394956 90)
			(size 0.381 1.27)
			(layers "F.Cu" "F.Mask" "F.Paste")
			(net "GND")
		)
		(pad "A3" smd rect
			(at 2.29997 -6.795008 90)
			(size 0.381 1.27)
			(layers "F.Cu" "F.Mask" "F.Paste")
			(net "GND")
		)
		(pad "A4" smd rect
			(at 2.29997 -6.19506 90)
			(size 0.381 1.27)
			(layers "F.Cu" "F.Mask" "F.Paste")
			(net "GND")
		)
		(pad "A5" smd rect
			(at 2.29997 -5.595112 90)
			(size 0.381 1.27)
			(layers "F.Cu" "F.Mask" "F.Paste")
			(net "GND")
		)
		(pad "A6" smd rect
			(at 2.29997 -4.99491 90)
			(size 0.381 1.27)
			(layers "F.Cu" "F.Mask" "F.Paste")
			(net "GND")
		)
		(pad "A7" smd rect
			(at 2.29997 -4.394962 90)
			(size 0.381 1.27)
			(layers "F.Cu" "F.Mask" "F.Paste")
			(net "SMB_ISO_SSD8_R_SCL")
		)
		(pad "A8" smd rect
			(at 2.29997 -3.795014 90)
			(size 0.381 1.27)
			(layers "F.Cu" "F.Mask" "F.Paste")
			(net "SMB_ISO_SSD8_R_SDA")
		)
		(pad "A9" smd rect
			(at 2.29997 -3.195066 90)
			(size 0.381 1.27)
			(layers "F.Cu" "F.Mask" "F.Paste")
			(net "RST_SMB_SSD8_ISO_R_N")
		)
		(pad "A10" smd rect
			(at 2.29997 -2.595118 90)
			(size 0.381 1.27)
			(layers "F.Cu" "F.Mask" "F.Paste")
			(net "SSD8_LED_ISO_R_N")
		)
		(pad "A11" smd rect
			(at 2.29997 -1.994916 90)
			(size 0.381 1.27)
			(layers "F.Cu" "F.Mask" "F.Paste")
			(net "PU_CLKREQ8")
		)
		(pad "A12" smd rect
			(at 2.29997 -1.394968 90)
			(size 0.381 1.27)
			(layers "F.Cu" "F.Mask" "F.Paste")
			(net "PRSNT_SSD8_N")
		)
		(pad "A13" smd rect
			(at 2.29997 -0.79502 90)
			(size 0.381 1.27)
			(layers "F.Cu" "F.Mask" "F.Paste")
			(net "GND")
		)
		(pad "A14" smd rect
			(at 2.29997 -0.195072 90)
			(size 0.381 1.27)
			(layers "F.Cu" "F.Mask" "F.Paste")
			(net "Net_8501")
		)
		(pad "A15" smd rect
			(at 2.29997 0.404876 90)
			(size 0.381 1.27)
			(layers "F.Cu" "F.Mask" "F.Paste")
			(net "Net_8500")
		)
		(pad "A16" smd rect
			(at 2.29997 1.005078 90)
			(size 0.381 1.27)
			(layers "F.Cu" "F.Mask" "F.Paste")
			(net "GND")
		)
		(pad "A17" smd rect
			(at 2.29997 1.605026 90)
			(size 0.381 1.27)
			(layers "F.Cu" "F.Mask" "F.Paste")
			(net "P5E_PEX2_STN2_RX_DN<44>")
		)
		(pad "A18" smd rect
			(at 2.29997 2.204974 90)
			(size 0.381 1.27)
			(layers "F.Cu" "F.Mask" "F.Paste")
			(net "P5E_PEX2_STN2_RX_DP<44>")
		)
		(pad "A19" smd rect
			(at 2.29997 2.804922 90)
			(size 0.381 1.27)
			(layers "F.Cu" "F.Mask" "F.Paste")
			(net "GND")
		)
		(pad "A20" smd rect
			(at 2.29997 3.405124 90)
			(size 0.381 1.27)
			(layers "F.Cu" "F.Mask" "F.Paste")
			(net "P5E_PEX2_STN2_RX_DN<45>")
		)
		(pad "A21" smd rect
			(at 2.29997 4.005072 90)
			(size 0.381 1.27)
			(layers "F.Cu" "F.Mask" "F.Paste")
			(net "P5E_PEX2_STN2_RX_DP<45>")
		)
		(pad "A22" smd rect
			(at 2.29997 4.60502 90)
			(size 0.381 1.27)
			(layers "F.Cu" "F.Mask" "F.Paste")
			(net "GND")
		)
		(pad "A23" smd rect
			(at 2.29997 5.204968 90)
			(size 0.381 1.27)
			(layers "F.Cu" "F.Mask" "F.Paste")
			(net "P5E_PEX2_STN2_RX_DN<46>")
		)
		(pad "A24" smd rect
			(at 2.29997 5.804916 90)
			(size 0.381 1.27)
			(layers "F.Cu" "F.Mask" "F.Paste")
			(net "P5E_PEX2_STN2_RX_DP<46>")
		)
		(pad "A25" smd rect
			(at 2.29997 6.405118 90)
			(size 0.381 1.27)
			(layers "F.Cu" "F.Mask" "F.Paste")
			(net "GND")
		)
		(pad "A26" smd rect
			(at 2.29997 7.005066 90)
			(size 0.381 1.27)
			(layers "F.Cu" "F.Mask" "F.Paste")
			(net "P5E_PEX2_STN2_RX_DN<47>")
		)
		(pad "A27" smd rect
			(at 2.29997 7.605014 90)
			(size 0.381 1.27)
			(layers "F.Cu" "F.Mask" "F.Paste")
			(net "P5E_PEX2_STN2_RX_DP<47>")
		)
		(pad "A28" smd rect
			(at 2.29997 8.204962 90)
			(size 0.381 1.27)
			(layers "F.Cu" "F.Mask" "F.Paste")
			(net "GND")
		)
		(pad "B1" smd rect
			(at -2.29997 -7.994904 90)
			(size 0.381 1.27)
			(layers "F.Cu" "F.Mask" "F.Paste")
			(net "P12V_SSD8")
		)
		(pad "B2" smd rect
			(at -2.29997 -7.394956 90)
			(size 0.381 1.27)
			(layers "F.Cu" "F.Mask" "F.Paste")
			(net "P12V_SSD8")
		)
		(pad "B3" smd rect
			(at -2.29997 -6.795008 90)
			(size 0.381 1.27)
			(layers "F.Cu" "F.Mask" "F.Paste")
			(net "P12V_SSD8")
		)
		(pad "B4" smd rect
			(at -2.29997 -6.19506 90)
			(size 0.381 1.27)
			(layers "F.Cu" "F.Mask" "F.Paste")
			(net "P12V_SSD8")
		)
		(pad "B5" smd rect
			(at -2.29997 -5.595112 90)
			(size 0.381 1.27)
			(layers "F.Cu" "F.Mask" "F.Paste")
			(net "P12V_SSD8")
		)
		(pad "B6" smd rect
			(at -2.29997 -4.99491 90)
			(size 0.381 1.27)
			(layers "F.Cu" "F.Mask" "F.Paste")
			(net "P12V_SSD8")
		)
		(pad "B7" smd rect
			(at -2.29997 -4.394962 90)
			(size 0.381 1.27)
			(layers "F.Cu" "F.Mask" "F.Paste")
			(net "Net_8502")
		)
		(pad "B8" smd rect
			(at -2.29997 -3.795014 90)
			(size 0.381 1.27)
			(layers "F.Cu" "F.Mask" "F.Paste")
			(net "Net_8499")
		)
		(pad "B9" smd rect
			(at -2.29997 -3.195066 90)
			(size 0.381 1.27)
			(layers "F.Cu" "F.Mask" "F.Paste")
			(net "DUALPORT_N_SSD8")
		)
		(pad "B10" smd rect
			(at -2.29997 -2.595118 90)
			(size 0.381 1.27)
			(layers "F.Cu" "F.Mask" "F.Paste")
			(net "RST_SSD8_PERST_R_N")
		)
		(pad "B11" smd rect
			(at -2.29997 -1.994916 90)
			(size 0.381 1.27)
			(layers "F.Cu" "F.Mask" "F.Paste")
			(net "P3V3_SSD8")
		)
		(pad "B12" smd rect
			(at -2.29997 -1.394968 90)
			(size 0.381 1.27)
			(layers "F.Cu" "F.Mask" "F.Paste")
			(net "SSD8_PWRDIS_R")
		)
		(pad "B13" smd rect
			(at -2.29997 -0.79502 90)
			(size 0.381 1.27)
			(layers "F.Cu" "F.Mask" "F.Paste")
			(net "GND")
		)
		(pad "B14" smd rect
			(at -2.29997 -0.195072 90)
			(size 0.381 1.27)
			(layers "F.Cu" "F.Mask" "F.Paste")
			(net "CLK_100M_DB800ZL_SSD8_R_DN")
		)
		(pad "B15" smd rect
			(at -2.29997 0.404876 90)
			(size 0.381 1.27)
			(layers "F.Cu" "F.Mask" "F.Paste")
			(net "CLK_100M_DB800ZL_SSD8_R_DP")
		)
		(pad "B16" smd rect
			(at -2.29997 1.005078 90)
			(size 0.381 1.27)
			(layers "F.Cu" "F.Mask" "F.Paste")
			(net "GND")
		)
		(pad "B17" smd rect
			(at -2.29997 1.605026 90)
			(size 0.381 1.27)
			(layers "F.Cu" "F.Mask" "F.Paste")
			(net "P5E_PEX2_STN2_TX_C_DN<44>")
		)
		(pad "B18" smd rect
			(at -2.29997 2.204974 90)
			(size 0.381 1.27)
			(layers "F.Cu" "F.Mask" "F.Paste")
			(net "P5E_PEX2_STN2_TX_C_DP<44>")
		)
		(pad "B19" smd rect
			(at -2.29997 2.804922 90)
			(size 0.381 1.27)
			(layers "F.Cu" "F.Mask" "F.Paste")
			(net "GND")
		)
		(pad "B20" smd rect
			(at -2.29997 3.405124 90)
			(size 0.381 1.27)
			(layers "F.Cu" "F.Mask" "F.Paste")
			(net "P5E_PEX2_STN2_TX_C_DN<45>")
		)
		(pad "B21" smd rect
			(at -2.29997 4.005072 90)
			(size 0.381 1.27)
			(layers "F.Cu" "F.Mask" "F.Paste")
			(net "P5E_PEX2_STN2_TX_C_DP<45>")
		)
		(pad "B22" smd rect
			(at -2.29997 4.60502 90)
			(size 0.381 1.27)
			(layers "F.Cu" "F.Mask" "F.Paste")
			(net "GND")
		)
		(pad "B23" smd rect
			(at -2.29997 5.204968 90)
			(size 0.381 1.27)
			(layers "F.Cu" "F.Mask" "F.Paste")
			(net "P5E_PEX2_STN2_TX_C_DN<46>")
		)
		(pad "B24" smd rect
			(at -2.29997 5.804916 90)
			(size 0.381 1.27)
			(layers "F.Cu" "F.Mask" "F.Paste")
			(net "P5E_PEX2_STN2_TX_C_DP<46>")
		)
		(pad "B25" smd rect
			(at -2.29997 6.405118 90)
			(size 0.381 1.27)
			(layers "F.Cu" "F.Mask" "F.Paste")
			(net "GND")
		)
		(pad "B26" smd rect
			(at -2.29997 7.005066 90)
			(size 0.381 1.27)
			(layers "F.Cu" "F.Mask" "F.Paste")
			(net "P5E_PEX2_STN2_TX_C_DN<47>")
		)
		(pad "B27" smd rect
			(at -2.29997 7.605014 90)
			(size 0.381 1.27)
			(layers "F.Cu" "F.Mask" "F.Paste")
			(net "P5E_PEX2_STN2_TX_C_DP<47>")
		)
		(pad "B28" smd rect
			(at -2.29997 8.204962 90)
			(size 0.381 1.27)
			(layers "F.Cu" "F.Mask" "F.Paste")
			(net "GND")
		)
		(pad "G1" thru_hole oval
			(at 0 -11.364976 90)
			(size 1.6256 3.4798)
			(drill oval 1.1176 2.4638)
			(layers "*.Cu" "*.Mask")
			(remove_unused_layers no)
			(net "GND")
			(clearance 0.127)
			(thermal_gap 0.127)
		)
		(pad "G2" thru_hole oval
			(at 0 11.364976 90)
			(size 1.6256 3.4798)
			(drill oval 1.1176 2.4638)
			(layers "*.Cu" "*.Mask")
			(remove_unused_layers no)
			(net "GND")
			(clearance 0.127)
			(thermal_gap 0.127)
		)
		(zone
			(layer "F.Cu")
			(hatch none 0.5)
			(connect_pads
				(clearance 0)
			)
			(min_thickness 0.25)
			(keepout
				(tracks not_allowed)
				(vias allowed)
				(pads allowed)
				(copperpour not_allowed)
				(footprints allowed)
			)
			(placement
				(enabled no)
				(sheetname "")
			)
			(fill
				(thermal_gap 0.5)
				(thermal_bridge_width 0.5)
				(island_removal_mode 0)
			)
			(polygon
				(pts
					(xy 246.544846 -38.850062) (xy 243.794788 -38.850062) (xy 243.794788 -35.900106) (xy 246.544846 -35.900106)
				)
			)
		)
		(zone
			(layer "F.Cu")
			(hatch none 0.5)
			(connect_pads
				(clearance 0)
			)
			(min_thickness 0.25)
			(keepout
				(tracks not_allowed)
				(vias allowed)
				(pads allowed)
				(copperpour not_allowed)
				(footprints allowed)
			)
			(placement
				(enabled no)
				(sheetname "")
			)
			(fill
				(thermal_gap 0.5)
				(thermal_bridge_width 0.5)
				(island_removal_mode 0)
			)
			(polygon
				(pts
					(xy 247.614948 -17.670018) (xy 243.784882 -17.670018) (xy 243.784882 -14.720062) (xy 247.614948 -14.720062)
				)
			)
		)
		(zone
			(layers "F.Cu" "B.Cu" "In1.Cu" "In2.Cu" "In3.Cu" "In4.Cu" "In5.Cu" "In6.Cu"
				"In7.Cu" "In8.Cu" "In9.Cu" "In10.Cu" "In11.Cu" "In12.Cu" "In13.Cu" "In14.Cu"
				"In15.Cu" "In16.Cu"
			)
			(hatch none 0.5)
			(connect_pads
				(clearance 0)
			)
			(min_thickness 0.25)
			(keepout
				(tracks not_allowed)
				(vias allowed)
				(pads allowed)
				(copperpour not_allowed)
				(footprints allowed)
			)
			(placement
				(enabled no)
				(sheetname "")
			)
			(fill
				(thermal_gap 0.5)
				(thermal_bridge_width 0.5)
				(island_removal_mode 0)
			)
			(polygon
				(pts
					(arc
						(start 246.130064 -36.60013)
						(mid 244.199664 -36.60013)
						(end 246.130064 -36.60013)
					)
				)
			)
		)
		(zone
			(layers "F.Cu" "B.Cu" "In1.Cu" "In2.Cu" "In3.Cu" "In4.Cu" "In5.Cu" "In6.Cu"
				"In7.Cu" "In8.Cu" "In9.Cu" "In10.Cu" "In11.Cu" "In12.Cu" "In13.Cu" "In14.Cu"
				"In15.Cu" "In16.Cu"
			)
			(hatch none 0.5)
			(connect_pads
				(clearance 0)
			)
			(min_thickness 0.25)
			(keepout
				(tracks not_allowed)
				(vias allowed)
				(pads allowed)
				(copperpour not_allowed)
				(footprints allowed)
			)
			(placement
				(enabled no)
				(sheetname "")
			)
			(fill
				(thermal_gap 0.5)
				(thermal_bridge_width 0.5)
				(island_removal_mode 0)
			)
			(polygon
				(pts
					(arc
						(start 247.880124 -16.969994)
						(mid 245.949724 -16.969994)
						(end 247.880124 -16.969994)
					)
				)
			)
		)
	)
	(footprint ""
		(layer "F.Cu")
		(at 53.126132 -37.929566 90)
		(property "Reference" "R5546"
			(at 0 0 90)
			(layer "F.SilkS")
			(hide yes)
			(effects
				(font
					(size 1.27 1.27)
				)
			)
		)
		(property "Value" ""
			(at 0 0 90)
			(layer "F.Fab")
			(effects
				(font
					(size 1.27 1.27)
				)
			)
		)
		(duplicate_pad_numbers_are_jumpers no)
		(fp_line
			(start 0.7874 -0.4064)
			(end 0.7874 0.4064)
			(stroke
				(width 0.1524)
				(type default)
			)
			(layer "F.SilkS")
		)
		(fp_line
			(start -0.7874 -0.4064)
			(end 0.7874 -0.4064)
			(stroke
				(width 0.1524)
				(type default)
			)
			(layer "F.SilkS")
		)
		(fp_line
			(start 0.7874 0.4064)
			(end -0.7874 0.4064)
			(stroke
				(width 0.1524)
				(type default)
			)
			(layer "F.SilkS")
		)
		(fp_line
			(start -0.7874 0.4064)
			(end -0.7874 -0.4064)
			(stroke
				(width 0.1524)
				(type default)
			)
			(layer "F.SilkS")
		)
		(fp_line
			(start -0.12065 -0.305054)
			(end -0.12065 -0.2794)
			(stroke
				(width 0.1)
				(type default)
			)
			(layer "F.Fab")
		)
		(fp_line
			(start -0.67945 -0.305054)
			(end -0.12065 -0.305054)
			(stroke
				(width 0.1)
				(type default)
			)
			(layer "F.Fab")
		)
		(fp_line
			(start 0.67945 -0.3048)
			(end 0.67945 0.3048)
			(stroke
				(width 0.1)
				(type default)
			)
			(layer "F.Fab")
		)
		(fp_line
			(start 0.12065 -0.3048)
			(end 0.67945 -0.3048)
			(stroke
				(width 0.1)
				(type default)
			)
			(layer "F.Fab")
		)
		(fp_line
			(start 0.12065 -0.2794)
			(end 0.12065 -0.3048)
			(stroke
				(width 0.1)
				(type default)
			)
			(layer "F.Fab")
		)
		(fp_line
			(start -0.12065 -0.2794)
			(end 0.12065 -0.2794)
			(stroke
				(width 0.1)
				(type default)
			)
			(layer "F.Fab")
		)
		(fp_line
			(start 0.120396 0.2794)
			(end -0.12065 0.2794)
			(stroke
				(width 0.1)
				(type default)
			)
			(layer "F.Fab")
		)
		(fp_line
			(start -0.12065 0.2794)
			(end -0.12065 0.3048)
			(stroke
				(width 0.1)
				(type default)
			)
			(layer "F.Fab")
		)
		(fp_line
			(start 0.67945 0.3048)
			(end 0.120396 0.3048)
			(stroke
				(width 0.1)
				(type default)
			)
			(layer "F.Fab")
		)
		(fp_line
			(start 0.120396 0.3048)
			(end 0.120396 0.2794)
			(stroke
				(width 0.1)
				(type default)
			)
			(layer "F.Fab")
		)
		(fp_line
			(start -0.12065 0.3048)
			(end -0.67945 0.3048)
			(stroke
				(width 0.1)
				(type default)
			)
			(layer "F.Fab")
		)
		(fp_line
			(start -0.67945 0.3048)
			(end -0.67945 -0.305054)
			(stroke
				(width 0.1)
				(type default)
			)
			(layer "F.Fab")
		)
		(pad "1" smd circle
			(at -0.40005 0 90)
			(size 0 0)
			(layers "F.Cu" "F.Mask" "F.Paste")
			(net "SSD2_AUX_P3V3_EN_R")
		)
		(pad "2" smd circle
			(at 0.40005 0 90)
			(size 0 0)
			(layers "F.Cu" "F.Mask" "F.Paste")
			(net "SSD2_AUX_P3V3_EN")
		)
	)
)
